(kicad_pcb
	(version 20260206)
	(generator "pcbnew")
	(generator_version "10.0")
	(general
		(thickness 1.6)
		(legacy_teardrops no)
	)
	(paper "A4")
	(title_block
		(title "01162023_DA0F0TEBIF0_F0T_Expander_BD_F_brd_V02_OCP.brd")
		(comment 1 "Grand Teton / footprints 4377-4381 of 9728")
	)
	(layers
		(0 "F.Cu" signal "TOP")
		(4 "In1.Cu" signal "GND")
		(6 "In2.Cu" signal "VCC")
		(8 "In3.Cu" signal "VCC1")
		(10 "In4.Cu" signal "GND1")
		(12 "In5.Cu" signal "IN1")
		(14 "In6.Cu" signal "GND2")
		(16 "In7.Cu" signal "IN2")
		(18 "In8.Cu" signal "GND3")
		(20 "In9.Cu" signal "IN3")
		(22 "In10.Cu" signal "GND4")
		(24 "In11.Cu" signal "IN4")
		(26 "In12.Cu" signal "GND5")
		(28 "In13.Cu" signal "IN5")
		(30 "In14.Cu" signal "GND6")
		(32 "In15.Cu" signal "IN6")
		(34 "In16.Cu" signal "GND7")
		(2 "B.Cu" signal "BOTTOM")
		(9 "F.Adhes" user "F.Adhesive")
		(11 "B.Adhes" user "B.Adhesive")
		(13 "F.Paste" user "Package Geometry/Pastemask Top")
		(15 "B.Paste" user "Package Geometry/Pastemask Bottom")
		(5 "F.SilkS" user "Ref Des/Silkscreen Top")
		(7 "B.SilkS" user "Ref Des/Silkscreen Bottom")
		(1 "F.Mask" user "Board Geometry/Soldermask Top")
		(3 "B.Mask" user "Board Geometry/Soldermask Bottom")
		(17 "Dwgs.User" user "User.Drawings")
		(19 "Cmts.User" user "User.Comments")
		(21 "Eco1.User" user "User.Eco1")
		(23 "Eco2.User" user "User.Eco2")
		(25 "Edge.Cuts" user "Board Geometry/Outline")
		(27 "Margin" user)
		(31 "F.CrtYd" user "Package Geometry/Place Bound Top")
		(29 "B.CrtYd" user "Package Geometry/Place Bound Bottom")
		(35 "F.Fab" user "Ref Des/Assembly Top")
		(33 "B.Fab" user "Ref Des/Assembly Bottom")
	)
	(footprint ""
		(layer "F.Cu")
		(at 279.14727 -21.37156)
		(property "Reference" "C3938"
			(at 0 0 0)
			(layer "F.SilkS")
			(hide yes)
			(effects
				(font
					(size 1.27 1.27)
				)
			)
		)
		(property "Value" ""
			(at 0 0 0)
			(layer "F.Fab")
			(effects
				(font
					(size 1.27 1.27)
				)
			)
		)
		(duplicate_pad_numbers_are_jumpers no)
		(fp_line
			(start -0.7874 -0.4064)
			(end 0.7874 -0.4064)
			(stroke
				(width 0.1524)
				(type default)
			)
			(layer "F.SilkS")
		)
		(fp_line
			(start -0.7874 0.4064)
			(end -0.7874 -0.4064)
			(stroke
				(width 0.1524)
				(type default)
			)
			(layer "F.SilkS")
		)
		(fp_line
			(start 0.7874 -0.4064)
			(end 0.7874 0.4064)
			(stroke
				(width 0.1524)
				(type default)
			)
			(layer "F.SilkS")
		)
		(fp_line
			(start 0.7874 0.4064)
			(end -0.7874 0.4064)
			(stroke
				(width 0.1524)
				(type default)
			)
			(layer "F.SilkS")
		)
		(fp_line
			(start -0.67945 -0.305054)
			(end -0.12065 -0.305054)
			(stroke
				(width 0.1)
				(type default)
			)
			(layer "F.Fab")
		)
		(fp_line
			(start -0.67945 0.3048)
			(end -0.67945 -0.305054)
			(stroke
				(width 0.1)
				(type default)
			)
			(layer "F.Fab")
		)
		(fp_line
			(start -0.12065 -0.305054)
			(end -0.12065 -0.2794)
			(stroke
				(width 0.1)
				(type default)
			)
			(layer "F.Fab")
		)
		(fp_line
			(start -0.12065 -0.2794)
			(end 0.12065 -0.2794)
			(stroke
				(width 0.1)
				(type default)
			)
			(layer "F.Fab")
		)
		(fp_line
			(start -0.12065 0.2794)
			(end -0.12065 0.3048)
			(stroke
				(width 0.1)
				(type default)
			)
			(layer "F.Fab")
		)
		(fp_line
			(start -0.12065 0.3048)
			(end -0.67945 0.3048)
			(stroke
				(width 0.1)
				(type default)
			)
			(layer "F.Fab")
		)
		(fp_line
			(start 0.120396 0.2794)
			(end -0.12065 0.2794)
			(stroke
				(width 0.1)
				(type default)
			)
			(layer "F.Fab")
		)
		(fp_line
			(start 0.120396 0.3048)
			(end 0.120396 0.2794)
			(stroke
				(width 0.1)
				(type default)
			)
			(layer "F.Fab")
		)
		(fp_line
			(start 0.12065 -0.3048)
			(end 0.67945 -0.3048)
			(stroke
				(width 0.1)
				(type default)
			)
			(layer "F.Fab")
		)
		(fp_line
			(start 0.12065 -0.2794)
			(end 0.12065 -0.3048)
			(stroke
				(width 0.1)
				(type default)
			)
			(layer "F.Fab")
		)
		(fp_line
			(start 0.67945 -0.3048)
			(end 0.67945 0.3048)
			(stroke
				(width 0.1)
				(type default)
			)
			(layer "F.Fab")
		)
		(fp_line
			(start 0.67945 0.3048)
			(end 0.120396 0.3048)
			(stroke
				(width 0.1)
				(type default)
			)
			(layer "F.Fab")
		)
		(pad "1" smd circle
			(at -0.40005 0)
			(size 0 0)
			(layers "F.Cu" "F.Mask" "F.Paste")
			(net "P12V_SSD9")
		)
		(pad "2" smd circle
			(at 0.40005 0)
			(size 0 0)
			(layers "F.Cu" "F.Mask" "F.Paste")
			(net "GND")
		)
	)
	(footprint ""
		(layer "F.Cu")
		(at 329.438 -85.598 180)
		(property "Reference" "R6260"
			(at 0 0 180)
			(layer "F.SilkS")
			(hide yes)
			(effects
				(font
					(size 1.27 1.27)
				)
			)
		)
		(property "Value" ""
			(at 0 0 180)
			(layer "F.Fab")
			(effects
				(font
					(size 1.27 1.27)
				)
			)
		)
		(duplicate_pad_numbers_are_jumpers no)
		(fp_line
			(start 0.7874 0.4064)
			(end -0.7874 0.4064)
			(stroke
				(width 0.1524)
				(type default)
			)
			(layer "F.SilkS")
		)
		(fp_line
			(start 0.7874 -0.4064)
			(end 0.7874 0.4064)
			(stroke
				(width 0.1524)
				(type default)
			)
			(layer "F.SilkS")
		)
		(fp_line
			(start -0.7874 0.4064)
			(end -0.7874 -0.4064)
			(stroke
				(width 0.1524)
				(type default)
			)
			(layer "F.SilkS")
		)
		(fp_line
			(start -0.7874 -0.4064)
			(end 0.7874 -0.4064)
			(stroke
				(width 0.1524)
				(type default)
			)
			(layer "F.SilkS")
		)
		(fp_line
			(start 0.67945 0.3048)
			(end 0.120396 0.3048)
			(stroke
				(width 0.1)
				(type default)
			)
			(layer "F.Fab")
		)
		(fp_line
			(start 0.67945 -0.3048)
			(end 0.67945 0.3048)
			(stroke
				(width 0.1)
				(type default)
			)
			(layer "F.Fab")
		)
		(fp_line
			(start 0.12065 -0.2794)
			(end 0.12065 -0.3048)
			(stroke
				(width 0.1)
				(type default)
			)
			(layer "F.Fab")
		)
		(fp_line
			(start 0.12065 -0.3048)
			(end 0.67945 -0.3048)
			(stroke
				(width 0.1)
				(type default)
			)
			(layer "F.Fab")
		)
		(fp_line
			(start 0.120396 0.3048)
			(end 0.120396 0.2794)
			(stroke
				(width 0.1)
				(type default)
			)
			(layer "F.Fab")
		)
		(fp_line
			(start 0.120396 0.2794)
			(end -0.12065 0.2794)
			(stroke
				(width 0.1)
				(type default)
			)
			(layer "F.Fab")
		)
		(fp_line
			(start -0.12065 0.3048)
			(end -0.67945 0.3048)
			(stroke
				(width 0.1)
				(type default)
			)
			(layer "F.Fab")
		)
		(fp_line
			(start -0.12065 0.2794)
			(end -0.12065 0.3048)
			(stroke
				(width 0.1)
				(type default)
			)
			(layer "F.Fab")
		)
		(fp_line
			(start -0.12065 -0.2794)
			(end 0.12065 -0.2794)
			(stroke
				(width 0.1)
				(type default)
			)
			(layer "F.Fab")
		)
		(fp_line
			(start -0.12065 -0.305054)
			(end -0.12065 -0.2794)
			(stroke
				(width 0.1)
				(type default)
			)
			(layer "F.Fab")
		)
		(fp_line
			(start -0.67945 0.3048)
			(end -0.67945 -0.305054)
			(stroke
				(width 0.1)
				(type default)
			)
			(layer "F.Fab")
		)
		(fp_line
			(start -0.67945 -0.305054)
			(end -0.12065 -0.305054)
			(stroke
				(width 0.1)
				(type default)
			)
			(layer "F.Fab")
		)
		(pad "1" smd circle
			(at -0.40005 0 180)
			(size 0 0)
			(layers "F.Cu" "F.Mask" "F.Paste")
			(net "SMB_ISO_CB_SDA")
		)
		(pad "2" smd circle
			(at 0.40005 0 180)
			(size 0 0)
			(layers "F.Cu" "F.Mask" "F.Paste")
			(net "P3V3")
		)
	)
	(footprint ""
		(layer "F.Cu")
		(at 412.378652 -356.244906 90)
		(property "Reference" "C2443"
			(at 0 0 90)
			(layer "F.SilkS")
			(hide yes)
			(effects
				(font
					(size 1.27 1.27)
				)
			)
		)
		(property "Value" ""
			(at 0 0 90)
			(layer "F.Fab")
			(effects
				(font
					(size 1.27 1.27)
				)
			)
		)
		(duplicate_pad_numbers_are_jumpers no)
		(fp_line
			(start 0.299974 -0.150114)
			(end 0.299974 0.150114)
			(stroke
				(width 0.1)
				(type default)
			)
			(layer "F.Fab")
		)
		(fp_line
			(start -0.299974 -0.150114)
			(end 0.299974 -0.150114)
			(stroke
				(width 0.1)
				(type default)
			)
			(layer "F.Fab")
		)
		(fp_line
			(start 0.299974 0.150114)
			(end -0.299974 0.150114)
			(stroke
				(width 0.1)
				(type default)
			)
			(layer "F.Fab")
		)
		(fp_line
			(start -0.299974 0.150114)
			(end -0.299974 -0.150114)
			(stroke
				(width 0.1)
				(type default)
			)
			(layer "F.Fab")
		)
		(pad "1" smd rect
			(at -0.2667 0 90)
			(size 0.3048 0.381)
			(layers "F.Cu" "F.Mask" "F.Paste")
			(net "P5E_PEX3_STN4_TX_DP<77>")
		)
		(pad "2" smd rect
			(at 0.2667 0 90)
			(size 0.3048 0.381)
			(layers "F.Cu" "F.Mask" "F.Paste")
			(net "P5E_PEX3_STN4_TX_C_DP<77>")
		)
	)
	(footprint ""
		(layer "F.Cu")
		(at 26.930096 -284.404308 -90)
		(property "Reference" "C3053"
			(at 0 0 270)
			(layer "F.SilkS")
			(hide yes)
			(effects
				(font
					(size 1.27 1.27)
				)
			)
		)
		(property "Value" ""
			(at 0 0 270)
			(layer "F.Fab")
			(effects
				(font
					(size 1.27 1.27)
				)
			)
		)
		(duplicate_pad_numbers_are_jumpers no)
		(fp_line
			(start -1.2954 0.5842)
			(end -1.2954 -0.5842)
			(stroke
				(width 0.1524)
				(type default)
			)
			(layer "F.SilkS")
		)
		(fp_line
			(start 1.2954 0.5842)
			(end -1.2954 0.5842)
			(stroke
				(width 0.1524)
				(type default)
			)
			(layer "F.SilkS")
		)
		(fp_line
			(start -1.2954 -0.5842)
			(end 1.2954 -0.5842)
			(stroke
				(width 0.1524)
				(type default)
			)
			(layer "F.SilkS")
		)
		(fp_line
			(start 1.2954 -0.5842)
			(end 1.2954 0.5842)
			(stroke
				(width 0.1524)
				(type default)
			)
			(layer "F.SilkS")
		)
		(fp_line
			(start -0.8636 0.4572)
			(end -0.8636 0.4064)
			(stroke
				(width 0.1)
				(type default)
			)
			(layer "F.Fab")
		)
		(fp_line
			(start 0.8636 0.4572)
			(end -0.8636 0.4572)
			(stroke
				(width 0.1)
				(type default)
			)
			(layer "F.Fab")
		)
		(fp_line
			(start -1.1938 0.4064)
			(end -1.1938 -0.4064)
			(stroke
				(width 0.1)
				(type default)
			)
			(layer "F.Fab")
		)
		(fp_line
			(start -0.8636 0.4064)
			(end -1.1938 0.4064)
			(stroke
				(width 0.1)
				(type default)
			)
			(layer "F.Fab")
		)
		(fp_line
			(start 0.8636 0.4064)
			(end 0.8636 0.4572)
			(stroke
				(width 0.1)
				(type default)
			)
			(layer "F.Fab")
		)
		(fp_line
			(start 1.1938 0.4064)
			(end 0.8636 0.4064)
			(stroke
				(width 0.1)
				(type default)
			)
			(layer "F.Fab")
		)
		(fp_line
			(start -1.1938 -0.4064)
			(end -0.8636 -0.4064)
			(stroke
				(width 0.1)
				(type default)
			)
			(layer "F.Fab")
		)
		(fp_line
			(start -0.8636 -0.4064)
			(end -0.8636 -0.4572)
			(stroke
				(width 0.1)
				(type default)
			)
			(layer "F.Fab")
		)
		(fp_line
			(start 0.8636 -0.4064)
			(end 1.1938 -0.4064)
			(stroke
				(width 0.1)
				(type default)
			)
			(layer "F.Fab")
		)
		(fp_line
			(start 1.1938 -0.4064)
			(end 1.1938 0.4064)
			(stroke
				(width 0.1)
				(type default)
			)
			(layer "F.Fab")
		)
		(fp_line
			(start -0.8636 -0.4572)
			(end 0.8636 -0.4572)
			(stroke
				(width 0.1)
				(type default)
			)
			(layer "F.Fab")
		)
		(fp_line
			(start 0.8636 -0.4572)
			(end 0.8636 -0.4064)
			(stroke
				(width 0.1)
				(type default)
			)
			(layer "F.Fab")
		)
		(pad "1" smd rect
			(at -0.7366 0 180)
			(size 0.7112 0.8128)
			(layers "F.Cu" "F.Mask" "F.Paste")
			(net "P1V8_PLL0_PEX0")
		)
		(pad "2" smd rect
			(at 0.7366 0 180)
			(size 0.7112 0.8128)
			(layers "F.Cu" "F.Mask" "F.Paste")
			(net "GND")
		)
	)
	(footprint ""
		(layer "F.Cu")
		(at 368.08283 -225.49993 180)
		(property "Reference" "JPEX3"
			(at 1.66243 -8.7884 0)
			(unlocked yes)
			(layer "F.SilkS")
			(effects
				(font
					(size 0.7874 0.5842)
					(thickness 0.1524)
				)
				(justify left)
			)
		)
		(property "Value" ""
			(at 0 0 180)
			(layer "F.Fab")
			(effects
				(font
					(size 1.27 1.27)
				)
			)
		)
		(duplicate_pad_numbers_are_jumpers no)
		(fp_line
			(start 12.46505 7.649972)
			(end -12.46505 7.649972)
			(stroke
				(width 0.1524)
				(type default)
			)
			(layer "F.SilkS")
		)
		(fp_line
			(start 12.46505 -7.649972)
			(end 12.46505 7.649972)
			(stroke
				(width 0.1524)
				(type default)
			)
			(layer "F.SilkS")
		)
		(fp_line
			(start 6.945122 7.649972)
			(end -6.945122 7.649972)
			(stroke
				(width 0.1524)
				(type default)
			)
			(layer "F.SilkS")
		)
		(fp_line
			(start 6.945122 -7.649972)
			(end 6.945122 7.649972)
			(stroke
				(width 0.1524)
				(type default)
			)
			(layer "F.SilkS")
		)
		(fp_line
			(start 6.945122 -7.649972)
			(end 0 -7.649972)
			(stroke
				(width 0.1524)
				(type default)
			)
			(layer "F.SilkS")
		)
		(fp_line
			(start 0 -7.649972)
			(end 12.46505 -7.649972)
			(stroke
				(width 0.1524)
				(type default)
			)
			(layer "F.SilkS")
		)
		(fp_line
			(start -6.945122 -7.649972)
			(end 0 -7.649972)
			(stroke
				(width 0.1524)
				(type default)
			)
			(layer "F.SilkS")
		)
		(fp_line
			(start -6.945122 -7.649972)
			(end -6.945122 7.649972)
			(stroke
				(width 0.1524)
				(type default)
			)
			(layer "F.SilkS")
		)
		(fp_line
			(start -12.46505 7.649972)
			(end -12.46505 5.641594)
			(stroke
				(width 0.1524)
				(type default)
			)
			(layer "F.SilkS")
		)
		(fp_line
			(start -12.46505 4.45262)
			(end -12.46505 4.123436)
			(stroke
				(width 0.1524)
				(type default)
			)
			(layer "F.SilkS")
		)
		(fp_line
			(start -12.46505 3.04419)
			(end -12.46505 -7.649972)
			(stroke
				(width 0.1524)
				(type default)
			)
			(layer "F.SilkS")
		)
		(fp_line
			(start -12.46505 -7.649972)
			(end 0 -7.649972)
			(stroke
				(width 0.1524)
				(type default)
			)
			(layer "F.SilkS")
		)
		(fp_poly
			(pts
				(xy -7.112 -4.445) (xy -8.128 -4.953) (xy -8.128 -3.937)
			)
			(stroke
				(width 0)
				(type default)
			)
			(fill yes)
			(layer "F.SilkS")
		)
		(fp_line
			(start 6.945122 7.649972)
			(end -6.945122 7.649972)
			(stroke
				(width 0.1)
				(type default)
			)
			(layer "F.Fab")
		)
		(fp_line
			(start 6.945122 -7.649972)
			(end 6.945122 7.649972)
			(stroke
				(width 0.1)
				(type default)
			)
			(layer "F.Fab")
		)
		(fp_line
			(start -6.945122 7.649972)
			(end -6.945122 -7.649972)
			(stroke
				(width 0.1)
				(type default)
			)
			(layer "F.Fab")
		)
		(fp_line
			(start -6.945122 -7.649972)
			(end 6.945122 -7.649972)
			(stroke
				(width 0.1)
				(type default)
			)
			(layer "F.Fab")
		)
		(fp_poly
			(pts
				(xy -7.112 -4.445) (xy -8.128 -4.953) (xy -8.128 -3.937)
			)
			(stroke
				(width 0)
				(type default)
			)
			(fill yes)
			(layer "F.Fab")
		)
		(fp_text user "9"
			(at 7.51713 4.1656 90)
			(unlocked yes)
			(layer "F.SilkS")
			(effects
				(font
					(size 0.7874 0.5842)
					(thickness 0.1524)
				)
				(justify left)
			)
		)
		(fp_text user "16"
			(at 7.49173 -5.2324 90)
			(unlocked yes)
			(layer "F.SilkS")
			(effects
				(font
					(size 0.7874 0.5842)
					(thickness 0.1524)
				)
				(justify left)
			)
		)
		(fp_text user "8"
			(at -7.77367 4.2164 90)
			(unlocked yes)
			(layer "F.SilkS")
			(effects
				(font
					(size 0.7874 0.5842)
					(thickness 0.1524)
				)
				(justify left)
			)
		)
		(fp_text user "9"
			(at 7.51713 4.1656 90)
			(unlocked yes)
			(layer "F.Fab")
			(effects
				(font
					(size 0.7874 0.5842)
					(thickness 0.1524)
				)
				(justify left)
			)
		)
		(fp_text user "16"
			(at 7.49173 -5.2324 90)
			(unlocked yes)
			(layer "F.Fab")
			(effects
				(font
					(size 0.7874 0.5842)
					(thickness 0.1524)
				)
				(justify left)
			)
		)
		(fp_text user "8"
			(at -7.77367 4.2164 90)
			(unlocked yes)
			(layer "F.Fab")
			(effects
				(font
					(size 0.7874 0.5842)
					(thickness 0.1524)
				)
				(justify left)
			)
		)
		(pad "1" smd rect
			(at -4.800092 -4.445 90)
			(size 0.508 1.524)
			(layers "F.Cu" "F.Mask" "F.Paste")
			(net "SPI_PEX3_SDIO3_R1")
		)
		(pad "2" smd rect
			(at -4.800092 -3.175 90)
			(size 0.508 1.524)
			(layers "F.Cu" "F.Mask" "F.Paste")
			(net "P1V8_PEX")
		)
		(pad "3" smd rect
			(at -4.800092 -1.905 90)
			(size 0.508 1.524)
			(layers "F.Cu" "F.Mask" "F.Paste")
			(net "SPI_PEX3_RST_R_N")
		)
		(pad "4" smd rect
			(at -4.800092 -0.635 90)
			(size 0.508 1.524)
			(layers "F.Cu" "F.Mask" "F.Paste")
			(net "Net_2705")
		)
		(pad "5" smd rect
			(at -4.800092 0.635 90)
			(size 0.508 1.524)
			(layers "F.Cu" "F.Mask" "F.Paste")
			(net "Net_2704")
		)
		(pad "6" smd rect
			(at -4.800092 1.905 90)
			(size 0.508 1.524)
			(layers "F.Cu" "F.Mask" "F.Paste")
			(net "Net_2703")
		)
		(pad "7" smd rect
			(at -4.800092 3.175 90)
			(size 0.508 1.524)
			(layers "F.Cu" "F.Mask" "F.Paste")
			(net "SPI_PEX3_CS_MUX_R_N")
		)
		(pad "8" smd rect
			(at -4.800092 4.445 90)
			(size 0.508 1.524)
			(layers "F.Cu" "F.Mask" "F.Paste")
			(net "SPI_PEX3_SDIO1_MUX_R")
		)
		(pad "9" smd rect
			(at 4.800092 4.445 90)
			(size 0.508 1.524)
			(layers "F.Cu" "F.Mask" "F.Paste")
			(net "SPI_PEX3_SDIO2_R1")
		)
		(pad "10" smd rect
			(at 4.800092 3.175 90)
			(size 0.508 1.524)
			(layers "F.Cu" "F.Mask" "F.Paste")
			(net "GND")
		)
		(pad "11" smd rect
			(at 4.800092 1.905 90)
			(size 0.508 1.524)
			(layers "F.Cu" "F.Mask" "F.Paste")
			(net "Net_2706")
		)
		(pad "12" smd rect
			(at 4.800092 0.635 90)
			(size 0.508 1.524)
			(layers "F.Cu" "F.Mask" "F.Paste")
			(net "Net_2707")
		)
		(pad "13" smd rect
			(at 4.800092 -0.635 90)
			(size 0.508 1.524)
			(layers "F.Cu" "F.Mask" "F.Paste")
			(net "Net_2708")
		)
		(pad "14" smd rect
			(at 4.800092 -1.905 90)
			(size 0.508 1.524)
			(layers "F.Cu" "F.Mask" "F.Paste")
			(net "Net_2709")
		)
		(pad "15" smd rect
			(at 4.800092 -3.175 90)
			(size 0.508 1.524)
			(layers "F.Cu" "F.Mask" "F.Paste")
			(net "SPI_PEX3_SDIO0_MUX_R")
		)
		(pad "16" smd rect
			(at 4.800092 -4.445 90)
			(size 0.508 1.524)
			(layers "F.Cu" "F.Mask" "F.Paste")
			(net "SPI_PEX3_CLK_MUX_R")
		)
	)
)
